(kicad_pcb
	(version 20260206)
	(generator "pcbnew")
	(generator_version "10.0")
	(general
		(thickness 1.6)
		(legacy_teardrops no)
	)
	(paper "A4")
	(title_block
		(title "04192023_DAF0TMB3IC0_F0TG_MB_C_brd_V02_OCP.brd")
		(comment 1 "Grand Teton / footprints 4445-4451 of 8354")
	)
	(layers
		(0 "F.Cu" signal "TOP")
		(4 "In1.Cu" signal "GND")
		(6 "In2.Cu" signal "IN1")
		(8 "In3.Cu" signal "GND1")
		(10 "In4.Cu" signal "IN2")
		(12 "In5.Cu" signal "GND2")
		(14 "In6.Cu" signal "IN3")
		(16 "In7.Cu" signal "GND3")
		(18 "In8.Cu" signal "VCC")
		(20 "In9.Cu" signal "VCC1")
		(22 "In10.Cu" signal "GND4")
		(24 "In11.Cu" signal "IN4")
		(26 "In12.Cu" signal "GND5")
		(28 "In13.Cu" signal "IN5")
		(30 "In14.Cu" signal "GND6")
		(32 "In15.Cu" signal "IN6")
		(34 "In16.Cu" signal "GND7")
		(2 "B.Cu" signal "BOTTOM")
		(9 "F.Adhes" user "F.Adhesive")
		(11 "B.Adhes" user "B.Adhesive")
		(13 "F.Paste" user "Package Geometry/Pastemask Top")
		(15 "B.Paste" user "Package Geometry/Pastemask Bottom")
		(5 "F.SilkS" user "Ref Des/Silkscreen Top")
		(7 "B.SilkS" user "Ref Des/Silkscreen Bottom")
		(1 "F.Mask" user "Board Geometry/Soldermask Top")
		(3 "B.Mask" user "Board Geometry/Soldermask Bottom")
		(17 "Dwgs.User" user "User.Drawings")
		(19 "Cmts.User" user "User.Comments")
		(21 "Eco1.User" user "User.Eco1")
		(23 "Eco2.User" user "User.Eco2")
		(25 "Edge.Cuts" user "Board Geometry/Outline")
		(27 "Margin" user)
		(31 "F.CrtYd" user "Package Geometry/Place Bound Top")
		(29 "B.CrtYd" user "Package Geometry/Place Bound Bottom")
		(35 "F.Fab" user "Ref Des/Assembly Top")
		(33 "B.Fab" user "Ref Des/Assembly Bottom")
	)
	(footprint ""
		(layer "F.Cu")
		(at 394.811758 -323.796152 90)
		(property "Reference" "R1505"
			(at 0 0 90)
			(layer "F.SilkS")
			(hide yes)
			(effects
				(font
					(size 1.27 1.27)
				)
			)
		)
		(property "Value" ""
			(at 0 0 90)
			(layer "F.Fab")
			(effects
				(font
					(size 1.27 1.27)
				)
			)
		)
		(duplicate_pad_numbers_are_jumpers no)
		(fp_line
			(start 0.7874 -0.4064)
			(end 0.7874 0.4064)
			(stroke
				(width 0.1524)
				(type default)
			)
			(layer "F.SilkS")
		)
		(fp_line
			(start -0.7874 -0.4064)
			(end 0.7874 -0.4064)
			(stroke
				(width 0.1524)
				(type default)
			)
			(layer "F.SilkS")
		)
		(fp_line
			(start 0.7874 0.4064)
			(end -0.7874 0.4064)
			(stroke
				(width 0.1524)
				(type default)
			)
			(layer "F.SilkS")
		)
		(fp_line
			(start -0.7874 0.4064)
			(end -0.7874 -0.4064)
			(stroke
				(width 0.1524)
				(type default)
			)
			(layer "F.SilkS")
		)
		(fp_line
			(start -0.12065 -0.305054)
			(end -0.12065 -0.2794)
			(stroke
				(width 0.1)
				(type default)
			)
			(layer "F.Fab")
		)
		(fp_line
			(start -0.67945 -0.305054)
			(end -0.12065 -0.305054)
			(stroke
				(width 0.1)
				(type default)
			)
			(layer "F.Fab")
		)
		(fp_line
			(start 0.67945 -0.3048)
			(end 0.67945 0.3048)
			(stroke
				(width 0.1)
				(type default)
			)
			(layer "F.Fab")
		)
		(fp_line
			(start 0.12065 -0.3048)
			(end 0.67945 -0.3048)
			(stroke
				(width 0.1)
				(type default)
			)
			(layer "F.Fab")
		)
		(fp_line
			(start 0.12065 -0.2794)
			(end 0.12065 -0.3048)
			(stroke
				(width 0.1)
				(type default)
			)
			(layer "F.Fab")
		)
		(fp_line
			(start -0.12065 -0.2794)
			(end 0.12065 -0.2794)
			(stroke
				(width 0.1)
				(type default)
			)
			(layer "F.Fab")
		)
		(fp_line
			(start 0.120396 0.2794)
			(end -0.12065 0.2794)
			(stroke
				(width 0.1)
				(type default)
			)
			(layer "F.Fab")
		)
		(fp_line
			(start -0.12065 0.2794)
			(end -0.12065 0.3048)
			(stroke
				(width 0.1)
				(type default)
			)
			(layer "F.Fab")
		)
		(fp_line
			(start 0.67945 0.3048)
			(end 0.120396 0.3048)
			(stroke
				(width 0.1)
				(type default)
			)
			(layer "F.Fab")
		)
		(fp_line
			(start 0.120396 0.3048)
			(end 0.120396 0.2794)
			(stroke
				(width 0.1)
				(type default)
			)
			(layer "F.Fab")
		)
		(fp_line
			(start -0.12065 0.3048)
			(end -0.67945 0.3048)
			(stroke
				(width 0.1)
				(type default)
			)
			(layer "F.Fab")
		)
		(fp_line
			(start -0.67945 0.3048)
			(end -0.67945 -0.305054)
			(stroke
				(width 0.1)
				(type default)
			)
			(layer "F.Fab")
		)
		(pad "1" smd circle
			(at -0.40005 0 90)
			(size 0 0)
			(layers "F.Cu" "F.Mask" "F.Paste")
			(net "PVDD18_S5_P0")
		)
		(pad "2" smd circle
			(at 0.40005 0 90)
			(size 0 0)
			(layers "F.Cu" "F.Mask" "F.Paste")
			(net "ESPI_CPU0_D2")
		)
	)
	(footprint ""
		(layer "F.Cu")
		(at 63.582804 -47.049944 90)
		(property "Reference" "H74"
			(at 0.04826 -7.363968 90)
			(unlocked yes)
			(layer "F.SilkS")
			(effects
				(font
					(size 0.7874 0.5842)
					(thickness 0.1524)
				)
			)
		)
		(property "Value" ""
			(at 0 0 90)
			(layer "F.Fab")
			(effects
				(font
					(size 1.27 1.27)
				)
			)
		)
		(duplicate_pad_numbers_are_jumpers no)
		(pad "" np_thru_hole circle
			(at 0 0 90)
			(size 0 0)
			(drill oval 3.2004 4.8006)
			(layers "*.Cu" "*.Mask")
			(clearance -1.2192)
			(thermal_gap 0.381)
			(padstack
				(mode front_inner_back)
				(layer "Inner"
					(shape oval)
					(size 3.2004 4.8006)
					(clearance 0.381)
				)
				(layer "B.Cu"
					(shape circle)
					(size 0 0)
					(clearance -1.2192)
				)
			)
		)
		(zone
			(layers "F.Cu" "B.Cu" "In1.Cu" "In2.Cu" "In3.Cu" "In4.Cu" "In5.Cu" "In6.Cu"
				"In7.Cu" "In8.Cu" "In9.Cu" "In10.Cu" "In11.Cu" "In12.Cu" "In13.Cu" "In14.Cu"
				"In15.Cu" "In16.Cu"
			)
			(hatch none 0.5)
			(connect_pads
				(clearance 0)
			)
			(min_thickness 0.25)
			(keepout
				(tracks not_allowed)
				(vias allowed)
				(pads allowed)
				(copperpour not_allowed)
				(footprints allowed)
			)
			(placement
				(enabled no)
				(sheetname "")
			)
			(fill
				(thermal_gap 0.5)
				(thermal_bridge_width 0.5)
				(island_removal_mode 0)
			)
			(polygon
				(pts
					(arc
						(start 64.382904 -49.158144)
						(mid 66.491104 -47.049944)
						(end 64.382904 -44.941744)
					)
					(arc
						(start 62.782704 -44.941744)
						(mid 60.674504 -47.049944)
						(end 62.782704 -49.158144)
					)
				)
			)
		)
		(zone
			(layers "F.Cu" "B.Cu" "In1.Cu" "In2.Cu" "In3.Cu" "In4.Cu" "In5.Cu" "In6.Cu"
				"In7.Cu" "In8.Cu" "In9.Cu" "In10.Cu" "In11.Cu" "In12.Cu" "In13.Cu" "In14.Cu"
				"In15.Cu" "In16.Cu"
			)
			(hatch none 0.5)
			(connect_pads
				(clearance 0)
			)
			(min_thickness 0.25)
			(keepout
				(tracks not_allowed)
				(vias allowed)
				(pads allowed)
				(copperpour not_allowed)
				(footprints allowed)
			)
			(placement
				(enabled no)
				(sheetname "")
			)
			(fill
				(thermal_gap 0.5)
				(thermal_bridge_width 0.5)
				(island_removal_mode 0)
			)
			(polygon
				(pts
					(arc
						(start 64.382904 -50.050192)
						(mid 67.383152 -47.049944)
						(end 64.382904 -44.049696)
					)
					(arc
						(start 62.782704 -44.049696)
						(mid 59.782456 -47.049944)
						(end 62.782704 -50.050192)
					)
				)
			)
		)
	)
	(footprint ""
		(layer "F.Cu")
		(at 196.536564 -71.836788 90)
		(property "Reference" "PC2200"
			(at 0 0 90)
			(layer "F.SilkS")
			(hide yes)
			(effects
				(font
					(size 1.27 1.27)
				)
			)
		)
		(property "Value" ""
			(at 0 0 90)
			(layer "F.Fab")
			(effects
				(font
					(size 1.27 1.27)
				)
			)
		)
		(duplicate_pad_numbers_are_jumpers no)
		(fp_line
			(start 0.7874 -0.4064)
			(end 0.7874 0.4064)
			(stroke
				(width 0.1524)
				(type default)
			)
			(layer "F.SilkS")
		)
		(fp_line
			(start -0.7874 -0.4064)
			(end 0.7874 -0.4064)
			(stroke
				(width 0.1524)
				(type default)
			)
			(layer "F.SilkS")
		)
		(fp_line
			(start 0.7874 0.4064)
			(end -0.7874 0.4064)
			(stroke
				(width 0.1524)
				(type default)
			)
			(layer "F.SilkS")
		)
		(fp_line
			(start -0.7874 0.4064)
			(end -0.7874 -0.4064)
			(stroke
				(width 0.1524)
				(type default)
			)
			(layer "F.SilkS")
		)
		(fp_line
			(start -0.12065 -0.305054)
			(end -0.12065 -0.2794)
			(stroke
				(width 0.1)
				(type default)
			)
			(layer "F.Fab")
		)
		(fp_line
			(start -0.67945 -0.305054)
			(end -0.12065 -0.305054)
			(stroke
				(width 0.1)
				(type default)
			)
			(layer "F.Fab")
		)
		(fp_line
			(start 0.67945 -0.3048)
			(end 0.67945 0.3048)
			(stroke
				(width 0.1)
				(type default)
			)
			(layer "F.Fab")
		)
		(fp_line
			(start 0.12065 -0.3048)
			(end 0.67945 -0.3048)
			(stroke
				(width 0.1)
				(type default)
			)
			(layer "F.Fab")
		)
		(fp_line
			(start 0.12065 -0.2794)
			(end 0.12065 -0.3048)
			(stroke
				(width 0.1)
				(type default)
			)
			(layer "F.Fab")
		)
		(fp_line
			(start -0.12065 -0.2794)
			(end 0.12065 -0.2794)
			(stroke
				(width 0.1)
				(type default)
			)
			(layer "F.Fab")
		)
		(fp_line
			(start 0.120396 0.2794)
			(end -0.12065 0.2794)
			(stroke
				(width 0.1)
				(type default)
			)
			(layer "F.Fab")
		)
		(fp_line
			(start -0.12065 0.2794)
			(end -0.12065 0.3048)
			(stroke
				(width 0.1)
				(type default)
			)
			(layer "F.Fab")
		)
		(fp_line
			(start 0.67945 0.3048)
			(end 0.120396 0.3048)
			(stroke
				(width 0.1)
				(type default)
			)
			(layer "F.Fab")
		)
		(fp_line
			(start 0.120396 0.3048)
			(end 0.120396 0.2794)
			(stroke
				(width 0.1)
				(type default)
			)
			(layer "F.Fab")
		)
		(fp_line
			(start -0.12065 0.3048)
			(end -0.67945 0.3048)
			(stroke
				(width 0.1)
				(type default)
			)
			(layer "F.Fab")
		)
		(fp_line
			(start -0.67945 0.3048)
			(end -0.67945 -0.305054)
			(stroke
				(width 0.1)
				(type default)
			)
			(layer "F.Fab")
		)
		(pad "1" smd circle
			(at -0.40005 0 90)
			(size 0 0)
			(layers "F.Cu" "F.Mask" "F.Paste")
			(net "P3V3_AUX")
		)
		(pad "2" smd circle
			(at 0.40005 0 90)
			(size 0 0)
			(layers "F.Cu" "F.Mask" "F.Paste")
			(net "GND")
		)
	)
	(footprint ""
		(layer "F.Cu")
		(at 16.422878 -16.099536 90)
		(property "Reference" "C679"
			(at 0 0 90)
			(layer "F.SilkS")
			(hide yes)
			(effects
				(font
					(size 1.27 1.27)
				)
			)
		)
		(property "Value" ""
			(at 0 0 90)
			(layer "F.Fab")
			(effects
				(font
					(size 1.27 1.27)
				)
			)
		)
		(duplicate_pad_numbers_are_jumpers no)
		(fp_line
			(start 0.299974 -0.150114)
			(end 0.299974 0.150114)
			(stroke
				(width 0.1)
				(type default)
			)
			(layer "F.Fab")
		)
		(fp_line
			(start -0.299974 -0.150114)
			(end 0.299974 -0.150114)
			(stroke
				(width 0.1)
				(type default)
			)
			(layer "F.Fab")
		)
		(fp_line
			(start 0.299974 0.150114)
			(end -0.299974 0.150114)
			(stroke
				(width 0.1)
				(type default)
			)
			(layer "F.Fab")
		)
		(fp_line
			(start -0.299974 0.150114)
			(end -0.299974 -0.150114)
			(stroke
				(width 0.1)
				(type default)
			)
			(layer "F.Fab")
		)
		(pad "1" smd rect
			(at -0.2667 0 90)
			(size 0.3048 0.381)
			(layers "F.Cu" "F.Mask" "F.Paste")
			(net "P5E_CPU1_G1_TX_C_DP<15>")
		)
		(pad "2" smd rect
			(at 0.2667 0 90)
			(size 0.3048 0.381)
			(layers "F.Cu" "F.Mask" "F.Paste")
			(net "P5E_CPU1_G1_TX_DP<15>")
		)
	)
	(footprint ""
		(layer "F.Cu")
		(at 200.600564 -69.804788 180)
		(property "Reference" "R3946"
			(at 0 0 180)
			(layer "F.SilkS")
			(hide yes)
			(effects
				(font
					(size 1.27 1.27)
				)
			)
		)
		(property "Value" ""
			(at 0 0 180)
			(layer "F.Fab")
			(effects
				(font
					(size 1.27 1.27)
				)
			)
		)
		(duplicate_pad_numbers_are_jumpers no)
		(fp_line
			(start 0.7874 0.4064)
			(end -0.7874 0.4064)
			(stroke
				(width 0.1524)
				(type default)
			)
			(layer "F.SilkS")
		)
		(fp_line
			(start 0.7874 -0.4064)
			(end 0.7874 0.4064)
			(stroke
				(width 0.1524)
				(type default)
			)
			(layer "F.SilkS")
		)
		(fp_line
			(start -0.7874 0.4064)
			(end -0.7874 -0.4064)
			(stroke
				(width 0.1524)
				(type default)
			)
			(layer "F.SilkS")
		)
		(fp_line
			(start -0.7874 -0.4064)
			(end 0.7874 -0.4064)
			(stroke
				(width 0.1524)
				(type default)
			)
			(layer "F.SilkS")
		)
		(fp_line
			(start 0.67945 0.3048)
			(end 0.120396 0.3048)
			(stroke
				(width 0.1)
				(type default)
			)
			(layer "F.Fab")
		)
		(fp_line
			(start 0.67945 -0.3048)
			(end 0.67945 0.3048)
			(stroke
				(width 0.1)
				(type default)
			)
			(layer "F.Fab")
		)
		(fp_line
			(start 0.12065 -0.2794)
			(end 0.12065 -0.3048)
			(stroke
				(width 0.1)
				(type default)
			)
			(layer "F.Fab")
		)
		(fp_line
			(start 0.12065 -0.3048)
			(end 0.67945 -0.3048)
			(stroke
				(width 0.1)
				(type default)
			)
			(layer "F.Fab")
		)
		(fp_line
			(start 0.120396 0.3048)
			(end 0.120396 0.2794)
			(stroke
				(width 0.1)
				(type default)
			)
			(layer "F.Fab")
		)
		(fp_line
			(start 0.120396 0.2794)
			(end -0.12065 0.2794)
			(stroke
				(width 0.1)
				(type default)
			)
			(layer "F.Fab")
		)
		(fp_line
			(start -0.12065 0.3048)
			(end -0.67945 0.3048)
			(stroke
				(width 0.1)
				(type default)
			)
			(layer "F.Fab")
		)
		(fp_line
			(start -0.12065 0.2794)
			(end -0.12065 0.3048)
			(stroke
				(width 0.1)
				(type default)
			)
			(layer "F.Fab")
		)
		(fp_line
			(start -0.12065 -0.2794)
			(end 0.12065 -0.2794)
			(stroke
				(width 0.1)
				(type default)
			)
			(layer "F.Fab")
		)
		(fp_line
			(start -0.12065 -0.305054)
			(end -0.12065 -0.2794)
			(stroke
				(width 0.1)
				(type default)
			)
			(layer "F.Fab")
		)
		(fp_line
			(start -0.67945 0.3048)
			(end -0.67945 -0.305054)
			(stroke
				(width 0.1)
				(type default)
			)
			(layer "F.Fab")
		)
		(fp_line
			(start -0.67945 -0.305054)
			(end -0.12065 -0.305054)
			(stroke
				(width 0.1)
				(type default)
			)
			(layer "F.Fab")
		)
		(pad "1" smd circle
			(at -0.40005 0 180)
			(size 0 0)
			(layers "F.Cu" "F.Mask" "F.Paste")
			(net "E1S_0_P3V3_EN")
		)
		(pad "2" smd circle
			(at 0.40005 0 180)
			(size 0 0)
			(layers "F.Cu" "F.Mask" "F.Paste")
			(net "P3V3_E1S_EN_0_R2")
		)
	)
	(footprint ""
		(layer "F.Cu")
		(at 360.987594 -320.132964 90)
		(property "Reference" "R8305"
			(at 0 0 90)
			(layer "F.SilkS")
			(hide yes)
			(effects
				(font
					(size 1.27 1.27)
				)
			)
		)
		(property "Value" ""
			(at 0 0 90)
			(layer "F.Fab")
			(effects
				(font
					(size 1.27 1.27)
				)
			)
		)
		(duplicate_pad_numbers_are_jumpers no)
		(fp_line
			(start -0.372364 -0.4064)
			(end 0.364236 -0.4064)
			(stroke
				(width 0.1524)
				(type default)
			)
			(layer "F.SilkS")
		)
		(fp_line
			(start 0.7874 0.073406)
			(end 0.7874 0.4064)
			(stroke
				(width 0.1524)
				(type default)
			)
			(layer "F.SilkS")
		)
		(fp_line
			(start 0.7874 0.4064)
			(end -0.7874 0.4064)
			(stroke
				(width 0.1524)
				(type default)
			)
			(layer "F.SilkS")
		)
		(fp_line
			(start -0.7874 0.4064)
			(end -0.7874 0.022606)
			(stroke
				(width 0.1524)
				(type default)
			)
			(layer "F.SilkS")
		)
		(fp_line
			(start -0.12065 -0.305054)
			(end -0.12065 -0.2794)
			(stroke
				(width 0.1)
				(type default)
			)
			(layer "F.Fab")
		)
		(fp_line
			(start -0.67945 -0.305054)
			(end -0.12065 -0.305054)
			(stroke
				(width 0.1)
				(type default)
			)
			(layer "F.Fab")
		)
		(fp_line
			(start 0.67945 -0.3048)
			(end 0.67945 0.3048)
			(stroke
				(width 0.1)
				(type default)
			)
			(layer "F.Fab")
		)
		(fp_line
			(start 0.12065 -0.3048)
			(end 0.67945 -0.3048)
			(stroke
				(width 0.1)
				(type default)
			)
			(layer "F.Fab")
		)
		(fp_line
			(start 0.12065 -0.2794)
			(end 0.12065 -0.3048)
			(stroke
				(width 0.1)
				(type default)
			)
			(layer "F.Fab")
		)
		(fp_line
			(start -0.12065 -0.2794)
			(end 0.12065 -0.2794)
			(stroke
				(width 0.1)
				(type default)
			)
			(layer "F.Fab")
		)
		(fp_line
			(start 0.120396 0.2794)
			(end -0.12065 0.2794)
			(stroke
				(width 0.1)
				(type default)
			)
			(layer "F.Fab")
		)
		(fp_line
			(start -0.12065 0.2794)
			(end -0.12065 0.3048)
			(stroke
				(width 0.1)
				(type default)
			)
			(layer "F.Fab")
		)
		(fp_line
			(start 0.67945 0.3048)
			(end 0.120396 0.3048)
			(stroke
				(width 0.1)
				(type default)
			)
			(layer "F.Fab")
		)
		(fp_line
			(start 0.120396 0.3048)
			(end 0.120396 0.2794)
			(stroke
				(width 0.1)
				(type default)
			)
			(layer "F.Fab")
		)
		(fp_line
			(start -0.12065 0.3048)
			(end -0.67945 0.3048)
			(stroke
				(width 0.1)
				(type default)
			)
			(layer "F.Fab")
		)
		(fp_line
			(start -0.67945 0.3048)
			(end -0.67945 -0.305054)
			(stroke
				(width 0.1)
				(type default)
			)
			(layer "F.Fab")
		)
		(pad "1" smd circle
			(at -0.40005 0 90)
			(size 0 0)
			(layers "F.Cu" "F.Mask" "F.Paste")
			(net "CLK_100M_CPU0_CLK13_R_DP")
		)
		(pad "2" smd circle
			(at 0.40005 0 90)
			(size 0 0)
			(layers "F.Cu" "F.Mask" "F.Paste")
			(net "CLK_100M_CPU0_CLK13_DP")
		)
	)
	(footprint ""
		(layer "F.Cu")
		(at 53.594 -435.229 -90)
		(property "Reference" "C1957"
			(at 0 0 270)
			(layer "F.SilkS")
			(hide yes)
			(effects
				(font
					(size 1.27 1.27)
				)
			)
		)
		(property "Value" ""
			(at 0 0 270)
			(layer "F.Fab")
			(effects
				(font
					(size 1.27 1.27)
				)
			)
		)
		(duplicate_pad_numbers_are_jumpers no)
		(fp_line
			(start -0.7874 0.4064)
			(end -0.7874 -0.4064)
			(stroke
				(width 0.1524)
				(type default)
			)
			(layer "F.SilkS")
		)
		(fp_line
			(start 0.7874 0.4064)
			(end -0.7874 0.4064)
			(stroke
				(width 0.1524)
				(type default)
			)
			(layer "F.SilkS")
		)
		(fp_line
			(start -0.7874 -0.4064)
			(end 0.7874 -0.4064)
			(stroke
				(width 0.1524)
				(type default)
			)
			(layer "F.SilkS")
		)
		(fp_line
			(start 0.7874 -0.4064)
			(end 0.7874 0.4064)
			(stroke
				(width 0.1524)
				(type default)
			)
			(layer "F.SilkS")
		)
		(fp_line
			(start -0.67945 0.3048)
			(end -0.67945 -0.305054)
			(stroke
				(width 0.1)
				(type default)
			)
			(layer "F.Fab")
		)
		(fp_line
			(start -0.12065 0.3048)
			(end -0.67945 0.3048)
			(stroke
				(width 0.1)
				(type default)
			)
			(layer "F.Fab")
		)
		(fp_line
			(start 0.120396 0.3048)
			(end 0.120396 0.2794)
			(stroke
				(width 0.1)
				(type default)
			)
			(layer "F.Fab")
		)
		(fp_line
			(start 0.67945 0.3048)
			(end 0.120396 0.3048)
			(stroke
				(width 0.1)
				(type default)
			)
			(layer "F.Fab")
		)
		(fp_line
			(start -0.12065 0.2794)
			(end -0.12065 0.3048)
			(stroke
				(width 0.1)
				(type default)
			)
			(layer "F.Fab")
		)
		(fp_line
			(start 0.120396 0.2794)
			(end -0.12065 0.2794)
			(stroke
				(width 0.1)
				(type default)
			)
			(layer "F.Fab")
		)
		(fp_line
			(start -0.12065 -0.2794)
			(end 0.12065 -0.2794)
			(stroke
				(width 0.1)
				(type default)
			)
			(layer "F.Fab")
		)
		(fp_line
			(start 0.12065 -0.2794)
			(end 0.12065 -0.3048)
			(stroke
				(width 0.1)
				(type default)
			)
			(layer "F.Fab")
		)
		(fp_line
			(start 0.12065 -0.3048)
			(end 0.67945 -0.3048)
			(stroke
				(width 0.1)
				(type default)
			)
			(layer "F.Fab")
		)
		(fp_line
			(start 0.67945 -0.3048)
			(end 0.67945 0.3048)
			(stroke
				(width 0.1)
				(type default)
			)
			(layer "F.Fab")
		)
		(fp_line
			(start -0.67945 -0.305054)
			(end -0.12065 -0.305054)
			(stroke
				(width 0.1)
				(type default)
			)
			(layer "F.Fab")
		)
		(fp_line
			(start -0.12065 -0.305054)
			(end -0.12065 -0.2794)
			(stroke
				(width 0.1)
				(type default)
			)
			(layer "F.Fab")
		)
		(pad "1" smd circle
			(at -0.40005 0 270)
			(size 0 0)
			(layers "F.Cu" "F.Mask" "F.Paste")
			(net "P3V3_AUX")
		)
		(pad "2" smd circle
			(at 0.40005 0 270)
			(size 0 0)
			(layers "F.Cu" "F.Mask" "F.Paste")
			(net "GND")
		)
	)
)
